# BASEBOARD_FAB2 (Tioga Pass) — schematic netlist excerpt (pin names and nets, part order shuffled) for the footprints in the layout excerpt that follows; sources: Cadence DE-HDL packaged netlist, KiCad conversion of Wiwynn_Tioga_Pass_MB.brd

L1D2  IND-120NH-30-GP  pkg DISCRET-GB2  page 208 : S = VR_PVCCIN_CPU1_PHASE3 ; F = PVCCIN_CPU1
C7B8  SC22U16V5MX-4-GP  20%  pkg SMD-BCG5  page 232 : \1\ = VR_FET_SW_P12V_STBY_PVPP_DEF ; \2\ = GND
R6D12  RES  49.9 1% CHIP  pkg 0402  page 96 : A = PVCCIO_CPU0 ; B = RST_CPU0_G_N

(kicad_pcb
	(version 20260206)
	(generator "pcbnew")
	(generator_version "10.0")
	(general
		(thickness 1.6)
		(legacy_teardrops no)
	)
	(paper "A4")
	(title_block
		(title "Wiwynn_Tioga_Pass_MB.brd")
		(comment 1 "Tioga Pass / footprints 480-482 of 4770")
	)
	(layers
		(0 "F.Cu" signal "TOP")
		(4 "In1.Cu" signal "L2GND")
		(6 "In2.Cu" signal "L3")
		(8 "In3.Cu" signal "L4GND")
		(10 "In4.Cu" signal "L5")
		(12 "In5.Cu" signal "L6GND")
		(14 "In6.Cu" signal "L7VCC")
		(16 "In7.Cu" signal "L8VCC")
		(18 "In8.Cu" signal "L9GND")
		(20 "In9.Cu" signal "L10")
		(22 "In10.Cu" signal "L11GND")
		(24 "In11.Cu" signal "L12")
		(26 "In12.Cu" signal "L13GND")
		(2 "B.Cu" signal "BOTTOM")
		(9 "F.Adhes" user "F.Adhesive")
		(11 "B.Adhes" user "B.Adhesive")
		(13 "F.Paste" user "Package Geometry/Pastemask Top")
		(15 "B.Paste" user "Package Geometry/Pastemask Bottom")
		(5 "F.SilkS" user "Ref Des/Silkscreen Top")
		(7 "B.SilkS" user "Ref Des/Silkscreen Bottom")
		(1 "F.Mask" user "Board Geometry/Soldermask Top")
		(3 "B.Mask" user "Board Geometry/Soldermask Bottom")
		(17 "Dwgs.User" user "User.Drawings")
		(19 "Cmts.User" user "User.Comments")
		(21 "Eco1.User" user "User.Eco1")
		(23 "Eco2.User" user "User.Eco2")
		(25 "Edge.Cuts" user "Board Geometry/Outline")
		(27 "Margin" user)
		(31 "F.CrtYd" user "Package Geometry/Place Bound Top")
		(29 "B.CrtYd" user "Package Geometry/Place Bound Bottom")
		(35 "F.Fab" user "Ref Des/Assembly Top")
		(33 "B.Fab" user "Ref Des/Assembly Bottom")
	)
	(footprint ""
		(layer "F.Cu")
		(at 279.82545 -70.438518 90)
		(property "Reference" "R6D12"
			(at 0 0 90)
			(layer "F.SilkS")
			(hide yes)
			(effects
				(font
					(size 1.27 1.27)
				)
			)
		)
		(property "Value" ""
			(at 0 0 90)
			(layer "F.Fab")
			(effects
				(font
					(size 1.27 1.27)
				)
			)
		)
		(duplicate_pad_numbers_are_jumpers no)
		(fp_poly
			(pts
				(xy -0.2794 -0.1016) (xy 0.2794 -0.1016) (xy 0.2794 0.9906) (xy -0.2794 0.9906)
			)
			(stroke
				(width 0)
				(type default)
			)
			(fill no)
			(layer "F.CrtYd")
		)
		(fp_line
			(start 0.2794 -0.1016)
			(end -0.2794 -0.1016)
			(stroke
				(width 0.1)
				(type default)
			)
			(layer "F.Fab")
		)
		(fp_line
			(start -0.2794 -0.1016)
			(end -0.2794 0.9906)
			(stroke
				(width 0.1)
				(type default)
			)
			(layer "F.Fab")
		)
		(fp_line
			(start 0.2794 0.9906)
			(end 0.2794 -0.1016)
			(stroke
				(width 0.1)
				(type default)
			)
			(layer "F.Fab")
		)
		(fp_line
			(start -0.2794 0.9906)
			(end 0.2794 0.9906)
			(stroke
				(width 0.1)
				(type default)
			)
			(layer "F.Fab")
		)
		(pad "1" smd rect
			(at 0 0 90)
			(size 0.508 0.508)
			(layers "F.Cu" "F.Mask" "F.Paste")
			(net "PVCCIO_CPU0")
		)
		(pad "2" smd rect
			(at 0 0.889 90)
			(size 0.508 0.508)
			(layers "F.Cu" "F.Mask" "F.Paste")
			(net "RST_CPU0_G_N")
		)
		(zone
			(layer "F.Cu")
			(hatch none 0.5)
			(connect_pads
				(clearance 0)
			)
			(min_thickness 0.25)
			(keepout
				(tracks allowed)
				(vias not_allowed)
				(pads allowed)
				(copperpour not_allowed)
				(footprints allowed)
			)
			(placement
				(enabled no)
				(sheetname "")
			)
			(fill
				(thermal_gap 0.5)
				(thermal_bridge_width 0.5)
				(island_removal_mode 0)
			)
			(polygon
				(pts
					(xy 280.07945 -70.184518) (xy 280.07945 -70.692518) (xy 280.46045 -70.692518) (xy 280.46045 -70.184518)
				)
			)
		)
		(zone
			(layer "F.Cu")
			(hatch none 0.5)
			(connect_pads
				(clearance 0)
			)
			(min_thickness 0.25)
			(keepout
				(tracks not_allowed)
				(vias allowed)
				(pads allowed)
				(copperpour not_allowed)
				(footprints allowed)
			)
			(placement
				(enabled no)
				(sheetname "")
			)
			(fill
				(thermal_gap 0.5)
				(thermal_bridge_width 0.5)
				(island_removal_mode 0)
			)
			(polygon
				(pts
					(xy 280.46045 -70.184518) (xy 280.46045 -70.692518) (xy 280.07945 -70.692518) (xy 280.07945 -70.184518)
				)
			)
		)
	)
	(footprint ""
		(layer "F.Cu")
		(at 40.036496 -73.287382)
		(property "Reference" "L1D2"
			(at 3.378708 -4.251706 0)
			(unlocked yes)
			(layer "F.SilkS")
			(effects
				(font
					(size 0.4064 0.254)
					(thickness 0.1524)
				)
			)
		)
		(property "Value" ""
			(at 0 0 0)
			(layer "F.Fab")
			(effects
				(font
					(size 1.27 1.27)
				)
			)
		)
		(duplicate_pad_numbers_are_jumpers no)
		(fp_line
			(start -1.1303 -3.199892)
			(end 8.3693 -3.199892)
			(stroke
				(width 0.1524)
				(type default)
			)
			(layer "F.SilkS")
		)
		(fp_line
			(start -1.1303 -1.6637)
			(end -1.1303 -3.199892)
			(stroke
				(width 0.1524)
				(type default)
			)
			(layer "F.SilkS")
		)
		(fp_line
			(start -1.1303 3.199892)
			(end -1.1303 1.6637)
			(stroke
				(width 0.1524)
				(type default)
			)
			(layer "F.SilkS")
		)
		(fp_line
			(start 8.3693 -3.199892)
			(end 8.3693 -1.6637)
			(stroke
				(width 0.1524)
				(type default)
			)
			(layer "F.SilkS")
		)
		(fp_line
			(start 8.3693 1.6637)
			(end 8.3693 3.199892)
			(stroke
				(width 0.1524)
				(type default)
			)
			(layer "F.SilkS")
		)
		(fp_line
			(start 8.3693 3.199892)
			(end -1.1303 3.199892)
			(stroke
				(width 0.1524)
				(type default)
			)
			(layer "F.SilkS")
		)
		(fp_rect
			(start -1.1303 3.199892)
			(end 8.3693 -3.199892)
			(stroke
				(width 0)
				(type default)
			)
			(fill no)
			(layer "F.CrtYd")
		)
		(fp_line
			(start -1.1303 -3.199892)
			(end 8.3693 -3.199892)
			(stroke
				(width 0.1)
				(type default)
			)
			(layer "F.Fab")
		)
		(fp_line
			(start -1.1303 3.199892)
			(end -1.1303 -3.199892)
			(stroke
				(width 0.1)
				(type default)
			)
			(layer "F.Fab")
		)
		(fp_line
			(start 8.3693 -3.199892)
			(end 8.3693 3.199892)
			(stroke
				(width 0.1)
				(type default)
			)
			(layer "F.Fab")
		)
		(fp_line
			(start 8.3693 3.199892)
			(end -1.1303 3.199892)
			(stroke
				(width 0.1)
				(type default)
			)
			(layer "F.Fab")
		)
		(pad "1" smd rect
			(at 0 0)
			(size 3.683 2.667)
			(layers "F.Cu" "F.Mask" "F.Paste")
			(net "VR_PVCCIN_CPU1_PHASE3")
		)
		(pad "2" smd rect
			(at 7.239 0)
			(size 3.683 2.667)
			(layers "F.Cu" "F.Mask" "F.Paste")
			(net "PVCCIN_CPU1")
		)
	)
	(footprint ""
		(layer "F.Cu")
		(at 351.028 -130.048 90)
		(property "Reference" "C7B8"
			(at 0 0 90)
			(layer "F.SilkS")
			(hide yes)
			(effects
				(font
					(size 1.27 1.27)
				)
			)
		)
		(property "Value" "*"
			(at -0.0762 -6.2357 90)
			(unlocked yes)
			(layer "F.Fab")
			(hide yes)
			(effects
				(font
					(size 1.27 1.016)
					(thickness 0.1524)
				)
			)
		)
		(property "Device Type" "SC22U16V5MX-4-GP_SMD-BCG5-SC22A"
			(at -0.0762 -8.2677 90)
			(unlocked yes)
			(layer "F.Fab")
			(hide yes)
			(effects
				(font
					(size 1.27 1.016)
					(thickness 0.1524)
				)
			)
		)
		(duplicate_pad_numbers_are_jumpers no)
		(fp_line
			(start 0.635 0)
			(end -0.635 0)
			(stroke
				(width 0.508)
				(type default)
			)
			(layer "F.SilkS")
		)
		(fp_rect
			(start -0.9652 1.778)
			(end 0.9652 -1.778)
			(stroke
				(width 0)
				(type default)
			)
			(fill no)
			(layer "F.CrtYd")
		)
		(fp_poly
			(pts
				(xy -0.9652 -1.778) (xy 0.9652 -1.778) (xy 0.9652 1.778) (xy -0.9652 1.778)
			)
			(stroke
				(width 0)
				(type default)
			)
			(fill no)
			(layer "F.Fab")
		)
		(pad "1" smd rect
			(at 0 -0.9652 90)
			(size 1.397 1.143)
			(layers "F.Cu" "F.Mask" "F.Paste")
			(net "VR_FET_SW_P12V_STBY_PVPP_DEF")
		)
		(pad "2" smd rect
			(at 0 0.9652 90)
			(size 1.397 1.143)
			(layers "F.Cu" "F.Mask" "F.Paste")
			(net "GND")
		)
	)
)
